(kicad_pcb
	(version 20260206)
	(generator "pcbnew")
	(generator_version "10.0")
	(general
		(thickness 1.6)
		(legacy_teardrops no)
	)
	(paper "A4")
	(title_block
		(title "Wiwynn_Tioga_Pass_MB.brd")
		(comment 1 "Tioga Pass / footprints 1005-1010 of 4770")
	)
	(layers
		(0 "F.Cu" signal "TOP")
		(4 "In1.Cu" signal "L2GND")
		(6 "In2.Cu" signal "L3")
		(8 "In3.Cu" signal "L4GND")
		(10 "In4.Cu" signal "L5")
		(12 "In5.Cu" signal "L6GND")
		(14 "In6.Cu" signal "L7VCC")
		(16 "In7.Cu" signal "L8VCC")
		(18 "In8.Cu" signal "L9GND")
		(20 "In9.Cu" signal "L10")
		(22 "In10.Cu" signal "L11GND")
		(24 "In11.Cu" signal "L12")
		(26 "In12.Cu" signal "L13GND")
		(2 "B.Cu" signal "BOTTOM")
		(9 "F.Adhes" user "F.Adhesive")
		(11 "B.Adhes" user "B.Adhesive")
		(13 "F.Paste" user "Package Geometry/Pastemask Top")
		(15 "B.Paste" user "Package Geometry/Pastemask Bottom")
		(5 "F.SilkS" user "Ref Des/Silkscreen Top")
		(7 "B.SilkS" user "Ref Des/Silkscreen Bottom")
		(1 "F.Mask" user "Board Geometry/Soldermask Top")
		(3 "B.Mask" user "Board Geometry/Soldermask Bottom")
		(17 "Dwgs.User" user "User.Drawings")
		(19 "Cmts.User" user "User.Comments")
		(21 "Eco1.User" user "User.Eco1")
		(23 "Eco2.User" user "User.Eco2")
		(25 "Edge.Cuts" user "Board Geometry/Outline")
		(27 "Margin" user)
		(31 "F.CrtYd" user "Package Geometry/Place Bound Top")
		(29 "B.CrtYd" user "Package Geometry/Place Bound Bottom")
		(35 "F.Fab" user "Ref Des/Assembly Top")
		(33 "B.Fab" user "Ref Des/Assembly Bottom")
	)
	(footprint ""
		(layer "F.Cu")
		(at 180.0606 -4.445 180)
		(property "Reference" "R4G19"
			(at 0 0 180)
			(layer "F.SilkS")
			(hide yes)
			(effects
				(font
					(size 1.27 1.27)
				)
			)
		)
		(property "Value" ""
			(at 0 0 180)
			(layer "F.Fab")
			(effects
				(font
					(size 1.27 1.27)
				)
			)
		)
		(duplicate_pad_numbers_are_jumpers no)
		(fp_poly
			(pts
				(xy -0.2794 -0.1016) (xy 0.2794 -0.1016) (xy 0.2794 0.9906) (xy -0.2794 0.9906)
			)
			(stroke
				(width 0)
				(type default)
			)
			(fill no)
			(layer "F.CrtYd")
		)
		(fp_line
			(start 0.2794 0.9906)
			(end 0.2794 -0.1016)
			(stroke
				(width 0.1)
				(type default)
			)
			(layer "F.Fab")
		)
		(fp_line
			(start 0.2794 -0.1016)
			(end -0.2794 -0.1016)
			(stroke
				(width 0.1)
				(type default)
			)
			(layer "F.Fab")
		)
		(fp_line
			(start -0.2794 0.9906)
			(end 0.2794 0.9906)
			(stroke
				(width 0.1)
				(type default)
			)
			(layer "F.Fab")
		)
		(fp_line
			(start -0.2794 -0.1016)
			(end -0.2794 0.9906)
			(stroke
				(width 0.1)
				(type default)
			)
			(layer "F.Fab")
		)
		(pad "1" smd rect
			(at 0 0 180)
			(size 0.508 0.508)
			(layers "F.Cu" "F.Mask" "F.Paste")
			(net "PWRGD_PVTT_ABC_CPU0_R")
		)
		(pad "2" smd rect
			(at 0 0.889 180)
			(size 0.508 0.508)
			(layers "F.Cu" "F.Mask" "F.Paste")
			(net "PWRGD_PVTT_CPU0")
		)
		(zone
			(layer "F.Cu")
			(hatch none 0.5)
			(connect_pads
				(clearance 0)
			)
			(min_thickness 0.25)
			(keepout
				(tracks not_allowed)
				(vias allowed)
				(pads allowed)
				(copperpour not_allowed)
				(footprints allowed)
			)
			(placement
				(enabled no)
				(sheetname "")
			)
			(fill
				(thermal_gap 0.5)
				(thermal_bridge_width 0.5)
				(island_removal_mode 0)
			)
			(polygon
				(pts
					(xy 180.3146 -5.08) (xy 179.8066 -5.08) (xy 179.8066 -4.699) (xy 180.3146 -4.699)
				)
			)
		)
		(zone
			(layer "F.Cu")
			(hatch none 0.5)
			(connect_pads
				(clearance 0)
			)
			(min_thickness 0.25)
			(keepout
				(tracks allowed)
				(vias not_allowed)
				(pads allowed)
				(copperpour not_allowed)
				(footprints allowed)
			)
			(placement
				(enabled no)
				(sheetname "")
			)
			(fill
				(thermal_gap 0.5)
				(thermal_bridge_width 0.5)
				(island_removal_mode 0)
			)
			(polygon
				(pts
					(xy 180.3146 -4.699) (xy 179.8066 -4.699) (xy 179.8066 -5.08) (xy 180.3146 -5.08)
				)
			)
		)
	)
	(footprint ""
		(layer "F.Cu")
		(at 351.83699 -148.646388 -90)
		(property "Reference" "CT46"
			(at 7.03707 4.2418 0)
			(unlocked yes)
			(layer "F.SilkS")
			(effects
				(font
					(size 0.7874 0.5842)
					(thickness 0.1524)
				)
				(justify left)
			)
		)
		(property "Value" ""
			(at 0 0 270)
			(layer "F.Fab")
			(effects
				(font
					(size 1.27 1.27)
				)
			)
		)
		(duplicate_pad_numbers_are_jumpers no)
		(fp_poly
			(pts
				(xy 0.3048 -0.1016) (xy 0.3048 0.9906) (xy -0.3048 0.9906) (xy -0.3048 -0.1016)
			)
			(stroke
				(width 0)
				(type default)
			)
			(fill no)
			(layer "F.CrtYd")
		)
		(fp_line
			(start -0.3048 0.9906)
			(end 0.3048 0.9906)
			(stroke
				(width 0.1)
				(type default)
			)
			(layer "F.Fab")
		)
		(fp_line
			(start 0.3048 0.9906)
			(end 0.3048 -0.1016)
			(stroke
				(width 0.1)
				(type default)
			)
			(layer "F.Fab")
		)
		(fp_line
			(start -0.3048 -0.1016)
			(end -0.3048 0.9906)
			(stroke
				(width 0.1)
				(type default)
			)
			(layer "F.Fab")
		)
		(fp_line
			(start 0.3048 -0.1016)
			(end -0.3048 -0.1016)
			(stroke
				(width 0.1)
				(type default)
			)
			(layer "F.Fab")
		)
		(pad "1" smd rect
			(at 0 0 270)
			(size 0.508 0.508)
			(layers "F.Cu" "F.Mask" "F.Paste")
			(net "VR_PVDDQ_DEF_AIREF2")
		)
		(pad "2" smd rect
			(at 0 0.889 270)
			(size 0.508 0.508)
			(layers "F.Cu" "F.Mask" "F.Paste")
			(net "GND")
		)
		(zone
			(layer "F.Cu")
			(hatch none 0.5)
			(connect_pads
				(clearance 0)
			)
			(min_thickness 0.25)
			(keepout
				(tracks not_allowed)
				(vias allowed)
				(pads allowed)
				(copperpour not_allowed)
				(footprints allowed)
			)
			(placement
				(enabled no)
				(sheetname "")
			)
			(fill
				(thermal_gap 0.5)
				(thermal_bridge_width 0.5)
				(island_removal_mode 0)
			)
			(polygon
				(pts
					(xy 351.20199 -148.900388) (xy 351.20199 -148.392388) (xy 351.58299 -148.392388) (xy 351.58299 -148.900388)
				)
			)
		)
		(zone
			(layer "F.Cu")
			(hatch none 0.5)
			(connect_pads
				(clearance 0)
			)
			(min_thickness 0.25)
			(keepout
				(tracks allowed)
				(vias not_allowed)
				(pads allowed)
				(copperpour not_allowed)
				(footprints allowed)
			)
			(placement
				(enabled no)
				(sheetname "")
			)
			(fill
				(thermal_gap 0.5)
				(thermal_bridge_width 0.5)
				(island_removal_mode 0)
			)
			(polygon
				(pts
					(xy 351.58299 -148.900388) (xy 351.58299 -148.392388) (xy 351.20199 -148.392388) (xy 351.20199 -148.900388)
				)
			)
		)
	)
	(footprint ""
		(layer "F.Cu")
		(at 184.531 -65.024)
		(property "Reference" "R4D67"
			(at 0 0 0)
			(layer "F.SilkS")
			(hide yes)
			(effects
				(font
					(size 1.27 1.27)
				)
			)
		)
		(property "Value" ""
			(at 0 0 0)
			(layer "F.Fab")
			(effects
				(font
					(size 1.27 1.27)
				)
			)
		)
		(duplicate_pad_numbers_are_jumpers no)
		(fp_rect
			(start -0.2794 0.9906)
			(end 0.2794 -0.1016)
			(stroke
				(width 0)
				(type default)
			)
			(fill no)
			(layer "F.CrtYd")
		)
		(fp_line
			(start -0.2794 -0.1016)
			(end -0.2794 0.9906)
			(stroke
				(width 0.1)
				(type default)
			)
			(layer "F.Fab")
		)
		(fp_line
			(start -0.2794 0.9906)
			(end 0.2794 0.9906)
			(stroke
				(width 0.1)
				(type default)
			)
			(layer "F.Fab")
		)
		(fp_line
			(start 0.2794 -0.1016)
			(end -0.2794 -0.1016)
			(stroke
				(width 0.1)
				(type default)
			)
			(layer "F.Fab")
		)
		(fp_line
			(start 0.2794 0.9906)
			(end 0.2794 -0.1016)
			(stroke
				(width 0.1)
				(type default)
			)
			(layer "F.Fab")
		)
		(pad "1" smd rect
			(at 0 0)
			(size 0.508 0.508)
			(layers "F.Cu" "F.Mask" "F.Paste")
			(net "SVID_VALERT_VCCIN_CPU0")
		)
		(pad "2" smd rect
			(at 0 0.889)
			(size 0.508 0.508)
			(layers "F.Cu" "F.Mask" "F.Paste")
			(net "SVID_ALERT0_CPU0_R_N")
		)
		(zone
			(layer "F.Cu")
			(hatch none 0.5)
			(connect_pads
				(clearance 0)
			)
			(min_thickness 0.25)
			(keepout
				(tracks allowed)
				(vias not_allowed)
				(pads allowed)
				(copperpour not_allowed)
				(footprints allowed)
			)
			(placement
				(enabled no)
				(sheetname "")
			)
			(fill
				(thermal_gap 0.5)
				(thermal_bridge_width 0.5)
				(island_removal_mode 0)
			)
			(polygon
				(pts
					(xy 184.277 -64.389) (xy 184.785 -64.389) (xy 184.785 -64.77) (xy 184.277 -64.77)
				)
			)
		)
		(zone
			(layer "F.Cu")
			(hatch none 0.5)
			(connect_pads
				(clearance 0)
			)
			(min_thickness 0.25)
			(keepout
				(tracks not_allowed)
				(vias allowed)
				(pads allowed)
				(copperpour not_allowed)
				(footprints allowed)
			)
			(placement
				(enabled no)
				(sheetname "")
			)
			(fill
				(thermal_gap 0.5)
				(thermal_bridge_width 0.5)
				(island_removal_mode 0)
			)
			(polygon
				(pts
					(xy 184.277 -64.389) (xy 184.785 -64.389) (xy 184.785 -64.77) (xy 184.277 -64.77)
				)
			)
		)
	)
	(footprint ""
		(layer "F.Cu")
		(at 477.8756 -48.9839)
		(property "Reference" "R9E7"
			(at 0 0 0)
			(layer "F.SilkS")
			(hide yes)
			(effects
				(font
					(size 1.27 1.27)
				)
			)
		)
		(property "Value" ""
			(at 0 0 0)
			(layer "F.Fab")
			(effects
				(font
					(size 1.27 1.27)
				)
			)
		)
		(duplicate_pad_numbers_are_jumpers no)
		(fp_poly
			(pts
				(xy -0.2794 -0.1016) (xy 0.2794 -0.1016) (xy 0.2794 0.9906) (xy -0.2794 0.9906)
			)
			(stroke
				(width 0)
				(type default)
			)
			(fill no)
			(layer "F.CrtYd")
		)
		(fp_line
			(start -0.2794 -0.1016)
			(end -0.2794 0.9906)
			(stroke
				(width 0.1)
				(type default)
			)
			(layer "F.Fab")
		)
		(fp_line
			(start -0.2794 0.9906)
			(end 0.2794 0.9906)
			(stroke
				(width 0.1)
				(type default)
			)
			(layer "F.Fab")
		)
		(fp_line
			(start 0.2794 -0.1016)
			(end -0.2794 -0.1016)
			(stroke
				(width 0.1)
				(type default)
			)
			(layer "F.Fab")
		)
		(fp_line
			(start 0.2794 0.9906)
			(end 0.2794 -0.1016)
			(stroke
				(width 0.1)
				(type default)
			)
			(layer "F.Fab")
		)
		(pad "1" smd rect
			(at 0 0)
			(size 0.508 0.508)
			(layers "F.Cu" "F.Mask" "F.Paste")
			(net "P3V3_STBY")
		)
		(pad "2" smd rect
			(at 0 0.889)
			(size 0.508 0.508)
			(layers "F.Cu" "F.Mask" "F.Paste")
			(net "IRQ_LOM_ALERT_N")
		)
		(zone
			(layer "F.Cu")
			(hatch none 0.5)
			(connect_pads
				(clearance 0)
			)
			(min_thickness 0.25)
			(keepout
				(tracks allowed)
				(vias not_allowed)
				(pads allowed)
				(copperpour not_allowed)
				(footprints allowed)
			)
			(placement
				(enabled no)
				(sheetname "")
			)
			(fill
				(thermal_gap 0.5)
				(thermal_bridge_width 0.5)
				(island_removal_mode 0)
			)
			(polygon
				(pts
					(xy 477.6216 -48.7299) (xy 478.1296 -48.7299) (xy 478.1296 -48.3489) (xy 477.6216 -48.3489)
				)
			)
		)
		(zone
			(layer "F.Cu")
			(hatch none 0.5)
			(connect_pads
				(clearance 0)
			)
			(min_thickness 0.25)
			(keepout
				(tracks not_allowed)
				(vias allowed)
				(pads allowed)
				(copperpour not_allowed)
				(footprints allowed)
			)
			(placement
				(enabled no)
				(sheetname "")
			)
			(fill
				(thermal_gap 0.5)
				(thermal_bridge_width 0.5)
				(island_removal_mode 0)
			)
			(polygon
				(pts
					(xy 477.6216 -48.3489) (xy 478.1296 -48.3489) (xy 478.1296 -48.7299) (xy 477.6216 -48.7299)
				)
			)
		)
	)
	(footprint ""
		(layer "F.Cu")
		(at 346.446094 -6.392418 -90)
		(property "Reference" "EU7G2"
			(at -5.112512 -1.254506 0)
			(unlocked yes)
			(layer "F.SilkS")
			(effects
				(font
					(size 0.7874 0.5842)
					(thickness 0.1524)
				)
			)
		)
		(property "Value" ""
			(at 0 0 270)
			(layer "F.Fab")
			(effects
				(font
					(size 1.27 1.27)
				)
			)
		)
		(duplicate_pad_numbers_are_jumpers no)
		(fp_line
			(start -3.0099 3.429)
			(end -3.0099 -3.5052)
			(stroke
				(width 0.1524)
				(type default)
			)
			(layer "F.SilkS")
		)
		(fp_line
			(start 2.9718 3.429)
			(end -3.0099 3.429)
			(stroke
				(width 0.1524)
				(type default)
			)
			(layer "F.SilkS")
		)
		(fp_line
			(start -3.0099 -3.5052)
			(end 2.9718 -3.5052)
			(stroke
				(width 0.1524)
				(type default)
			)
			(layer "F.SilkS")
		)
		(fp_line
			(start 2.9718 -3.5052)
			(end 2.9718 3.429)
			(stroke
				(width 0.1524)
				(type default)
			)
			(layer "F.SilkS")
		)
		(fp_circle
			(center -3.057398 -2.678684)
			(end -3.057398 -2.805684)
			(stroke
				(width 0.254)
				(type default)
			)
			(fill no)
			(layer "F.SilkS")
		)
		(fp_poly
			(pts
				(xy -2.9972 -3.4925) (xy -2.9972 -2.6924) (xy -2.1971 -3.4925)
			)
			(stroke
				(width 0)
				(type default)
			)
			(fill yes)
			(layer "F.SilkS")
		)
		(fp_poly
			(pts
				(xy -2.549906 -3.050032) (xy -2.549906 3.050032) (xy 2.549906 3.050032) (xy 2.549906 -3.050032)
			)
			(stroke
				(width 0)
				(type default)
			)
			(fill no)
			(layer "F.CrtYd")
		)
		(fp_line
			(start -2.549906 3.050032)
			(end -2.549906 -3.050032)
			(stroke
				(width 0.1)
				(type default)
			)
			(layer "F.Fab")
		)
		(fp_line
			(start 2.549906 3.050032)
			(end -2.549906 3.050032)
			(stroke
				(width 0.1)
				(type default)
			)
			(layer "F.Fab")
		)
		(fp_line
			(start -2.549906 -3.050032)
			(end 2.549906 -3.050032)
			(stroke
				(width 0.1)
				(type default)
			)
			(layer "F.Fab")
		)
		(fp_line
			(start 2.549906 -3.050032)
			(end 2.549906 3.050032)
			(stroke
				(width 0.1)
				(type default)
			)
			(layer "F.Fab")
		)
		(fp_circle
			(center -3.057398 -2.678684)
			(end -3.057398 -2.805684)
			(stroke
				(width 0.254)
				(type default)
			)
			(fill no)
			(layer "F.Fab")
		)
		(pad "1" smd rect
			(at -2.39522 -2.279904 270)
			(size 0.7112 0.254)
			(layers "F.Cu" "F.Mask" "F.Paste")
			(net "PVDDQ_ABC")
		)
		(pad "2" smd rect
			(at -2.39522 -1.83007 270)
			(size 0.7112 0.254)
			(layers "F.Cu" "F.Mask" "F.Paste")
			(net "GND")
		)
		(pad "3" smd rect
			(at -2.39522 -1.379982 270)
			(size 0.7112 0.254)
			(layers "F.Cu" "F.Mask" "F.Paste")
			(net "VR_PVDDQ_ABC_PH1_VCIN")
		)
		(pad "4" smd rect
			(at -2.39522 -0.929894 270)
			(size 0.7112 0.254)
			(layers "F.Cu" "F.Mask" "F.Paste")
			(net "P5V_STBY")
		)
		(pad "5" smd rect
			(at -2.39522 -0.48006 270)
			(size 0.7112 0.254)
			(layers "F.Cu" "F.Mask" "F.Paste")
			(net "GND")
		)
		(pad "6" smd rect
			(at -2.39522 -0.029972 270)
			(size 0.7112 0.254)
			(layers "F.Cu" "F.Mask" "F.Paste")
			(net "TP_PVDDQ_ABC_PH1_GL_0")
		)
		(pad "7" smd custom
			(at 0.016764 1.145032 270)
			(size 0.53975 0.53975)
			(layers "F.Cu" "F.Mask" "F.Paste")
			(net "GND")
			(options
				(clearance outline)
				(anchor circle)
			)
			(primitives
				(gr_poly
					(pts
						(xy -2.7051 1.0795) (xy -2.7051 -0.3683) (xy -0.9271 -0.3683) (xy -0.9271 -1.0795) (xy 2.7051 -1.0795)
						(xy 2.7051 1.0795)
					)
					(width 0)
					(fill yes)
				)
			)
		)
		(pad "10" smd rect
			(at -0.008382 2.874772 270)
			(size 4.3434 0.6096)
			(layers "F.Cu" "F.Mask" "F.Paste")
			(net "VR_PVDDQ_ABC_PH1_SW")
		)
		(pad "25" smd rect
			(at 1.548384 -1.283208 270)
			(size 2.3368 2.0066)
			(layers "F.Cu" "F.Mask" "F.Paste")
			(net "VR_FET_SW_P12V_STBY_PVDDQ_ABC")
		)
		(pad "30" smd rect
			(at 2.050034 -2.895092 270)
			(size 0.254 0.7112)
			(layers "F.Cu" "F.Mask" "F.Paste")
			(net "VR_FET_SW_P12V_STBY_PVDDQ_ABC")
		)
		(pad "31" smd rect
			(at 1.599946 -2.895092 270)
			(size 0.254 0.7112)
			(layers "F.Cu" "F.Mask" "F.Paste")
			(net "Net_368")
		)
		(pad "32" smd rect
			(at 1.150112 -2.895092 270)
			(size 0.254 0.7112)
			(layers "F.Cu" "F.Mask" "F.Paste")
			(net "VR_PVDDQ_ABC_PH1_PHASE")
		)
		(pad "33" smd rect
			(at 0.700024 -2.895092 270)
			(size 0.254 0.7112)
			(layers "F.Cu" "F.Mask" "F.Paste")
			(net "VR_PVDDQ_ABC_PH1_BOOT_R")
		)
		(pad "34" smd rect
			(at 0.249936 -2.895092 270)
			(size 0.254 0.7112)
			(layers "F.Cu" "F.Mask" "F.Paste")
			(net "VR_PVDDQ_ABC_PWM1")
		)
		(pad "35" smd rect
			(at -0.199898 -2.895092 270)
			(size 0.254 0.7112)
			(layers "F.Cu" "F.Mask" "F.Paste")
			(net "P5V_STBY")
		)
		(pad "36" smd rect
			(at -0.649986 -2.895092 270)
			(size 0.254 0.7112)
			(layers "F.Cu" "F.Mask" "F.Paste")
			(net "A_TSENSE_PVDDQ_ABC")
		)
		(pad "37" smd rect
			(at -1.100074 -2.895092 270)
			(size 0.254 0.7112)
			(layers "F.Cu" "F.Mask" "F.Paste")
			(net "VR_PVDDQ_ABC_PH1_OCSET")
		)
		(pad "38" smd rect
			(at -1.549908 -2.895092 270)
			(size 0.254 0.7112)
			(layers "F.Cu" "F.Mask" "F.Paste")
			(net "ISENSE_PVDDQ_ABC_PH1_IMON")
		)
		(pad "39" smd rect
			(at -1.999996 -2.895092 270)
			(size 0.254 0.7112)
			(layers "F.Cu" "F.Mask" "F.Paste")
			(net "VR_PVDDQ_ABC_AIREF1")
		)
		(pad "40" smd rect
			(at -0.871728 -1.283208 270)
			(size 1.8034 2.0066)
			(layers "F.Cu" "F.Mask" "F.Paste")
			(net "GND")
		)
		(pad "41" smd rect
			(at -1.533906 0.247904 270)
			(size 0.508 0.3556)
			(layers "F.Cu" "F.Mask" "F.Paste")
			(net "TP_PVDDQ_ABC_PH1_GL_1")
		)
	)
	(footprint ""
		(layer "F.Cu")
		(at 14.224 -75.311 180)
		(property "Reference" "R1D36"
			(at 0 0 180)
			(layer "F.SilkS")
			(hide yes)
			(effects
				(font
					(size 1.27 1.27)
				)
			)
		)
		(property "Value" ""
			(at 0 0 180)
			(layer "F.Fab")
			(effects
				(font
					(size 1.27 1.27)
				)
			)
		)
		(duplicate_pad_numbers_are_jumpers no)
		(fp_rect
			(start -0.2794 -0.1016)
			(end 0.2794 0.9906)
			(stroke
				(width 0)
				(type default)
			)
			(fill no)
			(layer "F.CrtYd")
		)
		(fp_line
			(start 0.2794 0.9906)
			(end 0.2794 -0.1016)
			(stroke
				(width 0.1)
				(type default)
			)
			(layer "F.Fab")
		)
		(fp_line
			(start 0.2794 -0.1016)
			(end -0.2794 -0.1016)
			(stroke
				(width 0.1)
				(type default)
			)
			(layer "F.Fab")
		)
		(fp_line
			(start -0.2794 0.9906)
			(end 0.2794 0.9906)
			(stroke
				(width 0.1)
				(type default)
			)
			(layer "F.Fab")
		)
		(fp_line
			(start -0.2794 -0.1016)
			(end -0.2794 0.9906)
			(stroke
				(width 0.1)
				(type default)
			)
			(layer "F.Fab")
		)
		(pad "1" smd rect
			(at 0 0 180)
			(size 0.508 0.508)
			(layers "F.Cu" "F.Mask" "F.Paste")
			(net "P12V_STBY")
		)
		(pad "2" smd rect
			(at 0 0.889 180)
			(size 0.508 0.508)
			(layers "F.Cu" "F.Mask" "F.Paste")
			(net "A_HSC_VOUT")
		)
		(zone
			(layer "F.Cu")
			(hatch none 0.5)
			(connect_pads
				(clearance 0)
			)
			(min_thickness 0.25)
			(keepout
				(tracks allowed)
				(vias not_allowed)
				(pads allowed)
				(copperpour not_allowed)
				(footprints allowed)
			)
			(placement
				(enabled no)
				(sheetname "")
			)
			(fill
				(thermal_gap 0.5)
				(thermal_bridge_width 0.5)
				(island_removal_mode 0)
			)
			(polygon
				(pts
					(xy 14.478 -75.565) (xy 14.478 -75.946) (xy 13.97 -75.946) (xy 13.97 -75.565)
				)
			)
		)
		(zone
			(layer "F.Cu")
			(hatch none 0.5)
			(connect_pads
				(clearance 0)
			)
			(min_thickness 0.25)
			(keepout
				(tracks not_allowed)
				(vias allowed)
				(pads allowed)
				(copperpour not_allowed)
				(footprints allowed)
			)
			(placement
				(enabled no)
				(sheetname "")
			)
			(fill
				(thermal_gap 0.5)
				(thermal_bridge_width 0.5)
				(island_removal_mode 0)
			)
			(polygon
				(pts
					(xy 14.478 -75.565) (xy 14.478 -75.946) (xy 13.97 -75.946) (xy 13.97 -75.565)
				)
			)
		)
	)
)
